# BARRELEYE-G2-EXPANDER-EVT-HW-EBOM-X00-20161124-add_2nd_source_X06-20161207-Final.xls — Single-Sole Source Parts List (bom)
| FOXCONN TECHNOLOGY GROUP |  |  |  |  |  |  |  |  |  |  |  |  |  |  |  |  |  |
| BILL OF MATERIAL |  |  |  |  |  |  |  |  |  |  |  |  |  |  |  |  |  |
| REV OF  BOM |  | CUSTOMER | <name> |  | CUSTOMER P/N |  | PWA P/N： | PWA DESCRIPTION |  |  | PRODUCT CODE |  |  | PWA REV |  | DATE |  |
| Sourcing (Single or Sole | Critical Commodity (Y or N) | Component Class (1, 2, Other) | Customer PSL (Y/N) | Item Number | Foxconn P/N | Customer P/N | Part Description | Mfr. 1 | Mfr Part # 1 | Proposed Mfr. 2 | Proposed Mfr. 2 PN | Qty | RoHS Status | Location | 2nd Source Qual Build: | Customer Comments | ODM Comments |
